#ISCELL
  mstr_misc dns *
  *
#ISCELL
  mstr_symbols bom_note *
  *
#ISCELL
  mstr_symbols cad_note *
  *
#ISCELL
  mstr_symbols intel_corp_bpage *
  *
#ISCELL
  mstr_standard offpage *
  page246_i1
#CELL
  mstr_discrete res *
  page246_i10
#CELL
  mstr_discrete res *
  page246_i11
#CELL
  mstr_discrete res *
  page246_i12
#ISCELL
  mstr_symbols gnd *
  page246_i13
#ISCELL
  mstr_symbols gnd *
  page246_i14
#CELL
  mstr_discrete cap *
  page246_i15
#CELL
  mstr_discrete cap *
  page246_i16
#CELL
  mstr_memory w25q256 *
  page246_i17
#ISCELL
  mstr_standard offpage *
  page246_i2
#ISCELL
  mstr_standard offpage *
  page246_i3
#ISCELL
  mstr_standard offpage *
  page246_i4
#CELL
  mstr_discrete res *
  page246_i5
#ISCELL
  mstr_symbols p3v3_stby *
  page246_i6
#ISCELL
  mstr_symbols gnd *
  page246_i7
#CELL
  mstr_discrete res *
  page246_i8
#CELL
  mstr_discrete res *
  page246_i9
